(kicad_pcb
	(version 20260206)
	(generator "pcbnew")
	(generator_version "10.0")
	(general
		(thickness 1.6)
		(legacy_teardrops no)
	)
	(paper "A4")
	(title_block
		(title "timecard-production-celestica-r4006 — R4006-B0001-02_R01.brd")
		(comment 1 "Time Appliance Project (Time Card) / footprints 474-479 of 1113")
	)
	(layers
		(0 "F.Cu" signal "TOP")
		(4 "In1.Cu" signal "L02_GND1")
		(6 "In2.Cu" signal "L03_SIG1")
		(8 "In3.Cu" signal "L04_GND2")
		(10 "In4.Cu" signal "L05_VCC1")
		(12 "In5.Cu" signal "L06_VCC2")
		(14 "In6.Cu" signal "L07_GND3")
		(16 "In7.Cu" signal "L08_SIG2")
		(18 "In8.Cu" signal "L09_GND4")
		(2 "B.Cu" signal "BOTTOM")
		(9 "F.Adhes" user "F.Adhesive")
		(11 "B.Adhes" user "B.Adhesive")
		(13 "F.Paste" user "Package Geometry/Pastemask Top")
		(15 "B.Paste" user "Package Geometry/Pastemask Bottom")
		(5 "F.SilkS" user "Ref Des/Silkscreen Top")
		(7 "B.SilkS" user "Ref Des/Silkscreen Bottom")
		(1 "F.Mask" user "Board Geometry/Soldermask Top")
		(3 "B.Mask" user "Board Geometry/Soldermask Bottom")
		(17 "Dwgs.User" user "User.Drawings")
		(19 "Cmts.User" user "User.Comments")
		(21 "Eco1.User" user "User.Eco1")
		(23 "Eco2.User" user "User.Eco2")
		(25 "Edge.Cuts" user "Board Geometry/Outline")
		(27 "Margin" user)
		(31 "F.CrtYd" user "Package Geometry/Place Bound Top")
		(29 "B.CrtYd" user "Package Geometry/Place Bound Bottom")
		(35 "F.Fab" user "Ref Des/Assembly Top")
		(33 "B.Fab" user "Ref Des/Assembly Bottom")
	)
	(footprint ""
		(layer "F.Cu")
		(at 65.000124 -78.650084)
		(property "Reference" "ME2"
			(at -0.928624 -4.368546 0)
			(unlocked yes)
			(layer "F.SilkS")
			(effects
				(font
					(size 0.7874 0.5842)
					(thickness 0.1524)
				)
				(justify left)
			)
		)
		(property "Value" ""
			(at 0 0 0)
			(layer "F.Fab")
			(effects
				(font
					(size 1.27 1.27)
				)
			)
		)
		(property "User Part Number" "PARTNUM*"
			(at -3.048 5.242306 0)
			(unlocked yes)
			(layer "Cmts.User")
			(hide yes)
			(effects
				(font
					(size 0.7874 0.5842)
					(thickness 0.1524)
				)
				(justify left)
			)
		)
		(property "Device Type" "NUT-G340-10437-01"
			(at -1.4732 4.226306 0)
			(unlocked yes)
			(layer "F.Fab")
			(hide yes)
			(effects
				(font
					(size 0.7874 0.5842)
					(thickness 0.1524)
				)
				(justify left)
			)
		)
		(duplicate_pad_numbers_are_jumpers no)
		(fp_circle
			(center 0 0)
			(end 3.3528 0)
			(stroke
				(width 0.1)
				(type default)
			)
			(fill no)
			(layer "F.SilkS")
		)
		(fp_poly
			(pts
				(arc
					(start -2.102612 -0.1524)
					(mid -1.490671 -1.490671)
					(end -0.1524 -2.102612)
				)
				(arc
					(start -0.1524 -3.171444)
					(mid -2.245137 -2.245137)
					(end -3.171444 -0.1524)
				)
			)
			(stroke
				(width 0)
				(type default)
			)
			(fill yes)
			(layer "F.Paste")
		)
		(fp_poly
			(pts
				(arc
					(start -0.1524 2.102612)
					(mid -1.490671 1.490671)
					(end -2.102612 0.1524)
				)
				(arc
					(start -3.171444 0.1524)
					(mid -2.245137 2.245137)
					(end -0.1524 3.171444)
				)
			)
			(stroke
				(width 0)
				(type default)
			)
			(fill yes)
			(layer "F.Paste")
		)
		(fp_poly
			(pts
				(arc
					(start 0.1524 -2.102612)
					(mid 1.490671 -1.490671)
					(end 2.102612 -0.1524)
				)
				(arc
					(start 3.171444 -0.1524)
					(mid 2.245137 -2.245137)
					(end 0.1524 -3.171444)
				)
			)
			(stroke
				(width 0)
				(type default)
			)
			(fill yes)
			(layer "F.Paste")
		)
		(fp_poly
			(pts
				(arc
					(start 2.102612 0.1524)
					(mid 1.490671 1.490671)
					(end 0.1524 2.102612)
				)
				(arc
					(start 0.1524 3.171444)
					(mid 2.245137 2.245137)
					(end 3.171444 0.1524)
				)
			)
			(stroke
				(width 0)
				(type default)
			)
			(fill yes)
			(layer "F.Paste")
		)
		(fp_rect
			(start -7.5946 7.5946)
			(end 7.5946 -7.5946)
			(stroke
				(width 0)
				(type default)
			)
			(fill no)
			(layer "B.CrtYd")
		)
		(fp_poly
			(pts
				(arc
					(start 3.6068 0)
					(mid -3.6068 0)
					(end 3.6068 0)
				)
			)
			(stroke
				(width 0)
				(type default)
			)
			(fill no)
			(layer "F.CrtYd")
		)
		(fp_circle
			(center 0 0)
			(end 2.8448 0)
			(stroke
				(width 0.1)
				(type default)
			)
			(fill no)
			(layer "F.Fab")
		)
		(pad "1" thru_hole circle
			(at 0 0)
			(size 6.1976 6.1976)
			(drill 4.2164)
			(layers "*.Cu" "*.Mask")
			(remove_unused_layers no)
			(net "SG")
			(padstack
				(mode front_inner_back)
				(layer "Inner"
					(shape circle)
					(size 5.0292 5.0292)
					(clearance -0.1143)
				)
				(layer "B.Cu"
					(shape circle)
					(size 5.0292 5.0292)
				)
			)
		)
	)
	(footprint ""
		(layer "F.Cu")
		(at 142.24 -101.854)
		(property "Reference" "TP36"
			(at 0.4826 0.15875 0)
			(unlocked yes)
			(layer "F.SilkS")
			(effects
				(font
					(size 0.635 0.4064)
					(thickness 0.1524)
				)
				(justify left)
			)
		)
		(property "Value" ""
			(at 0 0 0)
			(layer "F.Fab")
			(effects
				(font
					(size 1.27 1.27)
				)
			)
		)
		(property "Device Type" "TP_PIONT-TP010CT020B030_PTH-TPA"
			(at -1.341882 0.996696 0)
			(unlocked yes)
			(layer "F.Fab")
			(hide yes)
			(effects
				(font
					(size 0.7874 0.5842)
					(thickness 0.000001)
				)
				(justify left)
			)
		)
		(duplicate_pad_numbers_are_jumpers no)
		(fp_poly
			(pts
				(arc
					(start 0.889 0)
					(mid -0.889 0)
					(end 0.889 0)
				)
			)
			(stroke
				(width 0)
				(type default)
			)
			(fill no)
			(layer "B.CrtYd")
		)
		(fp_poly
			(pts
				(arc
					(start 0.889 0)
					(mid -0.889 0)
					(end 0.889 0)
				)
			)
			(stroke
				(width 0)
				(type default)
			)
			(fill no)
			(layer "F.CrtYd")
		)
		(pad "1" thru_hole circle
			(at 0 0)
			(size 0.508 0.508)
			(drill 0.254)
			(layers "*.Cu" "*.Mask")
			(remove_unused_layers no)
			(net "XP12R0V_A_PG")
			(clearance 0.1016)
			(padstack
				(mode front_inner_back)
				(layer "Inner"
					(shape circle)
					(size 0.508 0.508)
					(clearance 0.1016)
				)
				(layer "B.Cu"
					(shape circle)
					(size 0.762 0.762)
					(clearance -0.0254)
				)
			)
		)
	)
	(footprint ""
		(layer "F.Cu")
		(at 111.125 -99.441 180)
		(property "Reference" "R324"
			(at -3.302 3.13563 0)
			(unlocked yes)
			(layer "F.SilkS")
			(effects
				(font
					(size 0.7874 0.5842)
					(thickness 0.1524)
				)
			)
		)
		(property "Value" "VAL*"
			(at 0.02032 2.13233 180)
			(unlocked yes)
			(layer "F.Fab")
			(hide yes)
			(effects
				(font
					(size 0.7874 0.5842)
					(thickness 0.1524)
				)
			)
		)
		(property "Tolerance" "TOL*"
			(at 0.044704 3.05435 180)
			(unlocked yes)
			(layer "Cmts.User")
			(hide yes)
			(effects
				(font
					(size 0.7874 0.5842)
					(thickness 0.1524)
				)
			)
		)
		(property "User Part Number" "PARTNUM*"
			(at 0.02032 4.024884 180)
			(unlocked yes)
			(layer "Cmts.User")
			(hide yes)
			(effects
				(font
					(size 0.7874 0.5842)
					(thickness 0.1524)
				)
			)
		)
		(property "Device Type" "RESISTOR-G155-100R0-J0,0OHM,-"
			(at 0.008382 1.210564 180)
			(unlocked yes)
			(layer "F.Fab")
			(hide yes)
			(effects
				(font
					(size 0.7874 0.5842)
					(thickness 0.1524)
				)
			)
		)
		(duplicate_pad_numbers_are_jumpers no)
		(fp_line
			(start 1.143 0.5588)
			(end 1.143 -0.5588)
			(stroke
				(width 0.1)
				(type default)
			)
			(layer "F.SilkS")
		)
		(fp_line
			(start 1.143 -0.5588)
			(end -1.143 -0.5588)
			(stroke
				(width 0.1)
				(type default)
			)
			(layer "F.SilkS")
		)
		(fp_line
			(start -1.143 0.5588)
			(end 1.143 0.5588)
			(stroke
				(width 0.1)
				(type default)
			)
			(layer "F.SilkS")
		)
		(fp_line
			(start -1.143 -0.5588)
			(end -1.143 0.5588)
			(stroke
				(width 0.1)
				(type default)
			)
			(layer "F.SilkS")
		)
		(fp_poly
			(pts
				(xy -1.143 0.5588) (xy 1.143 0.5588) (xy 1.143 -0.5588) (xy -1.143 -0.5588)
			)
			(stroke
				(width 0)
				(type default)
			)
			(fill no)
			(layer "F.CrtYd")
		)
		(fp_line
			(start 0.508 0.3048)
			(end 0.508 -0.3048)
			(stroke
				(width 0.1)
				(type default)
			)
			(layer "F.Fab")
		)
		(fp_line
			(start 0.508 -0.3048)
			(end -0.508 -0.3048)
			(stroke
				(width 0.1)
				(type default)
			)
			(layer "F.Fab")
		)
		(fp_line
			(start -0.508 0.3048)
			(end 0.508 0.3048)
			(stroke
				(width 0.1)
				(type default)
			)
			(layer "F.Fab")
		)
		(fp_line
			(start -0.508 -0.3048)
			(end -0.508 0.3048)
			(stroke
				(width 0.1)
				(type default)
			)
			(layer "F.Fab")
		)
		(pad "1" smd rect
			(at -0.5334 0 180)
			(size 0.7112 0.6096)
			(layers "F.Cu" "F.Mask" "F.Paste")
			(net "SG")
		)
		(pad "2" smd rect
			(at 0.5334 0 180)
			(size 0.7112 0.6096)
			(layers "F.Cu" "F.Mask" "F.Paste")
			(net "UNNAMED_14_IS32FL3207QWLA3TRQFN")
		)
		(zone
			(layer "F.Cu")
			(hatch none 0.5)
			(connect_pads
				(clearance 0)
			)
			(min_thickness 0.25)
			(keepout
				(tracks allowed)
				(vias not_allowed)
				(pads allowed)
				(copperpour not_allowed)
				(footprints allowed)
			)
			(placement
				(enabled no)
				(sheetname "")
			)
			(fill
				(thermal_gap 0.5)
				(thermal_bridge_width 0.5)
				(island_removal_mode 0)
			)
			(polygon
				(pts
					(xy 111.2012 -99.7458) (xy 111.0488 -99.7458) (xy 111.0488 -99.1362) (xy 111.2012 -99.1362)
				)
			)
		)
		(zone
			(layer "F.Cu")
			(hatch none 0.5)
			(connect_pads
				(clearance 0)
			)
			(min_thickness 0.25)
			(keepout
				(tracks not_allowed)
				(vias allowed)
				(pads allowed)
				(copperpour not_allowed)
				(footprints allowed)
			)
			(placement
				(enabled no)
				(sheetname "")
			)
			(fill
				(thermal_gap 0.5)
				(thermal_bridge_width 0.5)
				(island_removal_mode 0)
			)
			(polygon
				(pts
					(xy 111.2012 -99.7458) (xy 111.0488 -99.7458) (xy 111.0488 -99.1362) (xy 111.2012 -99.1362)
				)
			)
		)
	)
	(footprint ""
		(layer "F.Cu")
		(at 150.381462 -59.182 180)
		(property "Reference" "R298"
			(at 1.410462 3.89763 0)
			(unlocked yes)
			(layer "F.SilkS")
			(effects
				(font
					(size 0.7874 0.5842)
					(thickness 0.1524)
				)
			)
		)
		(property "Value" "VAL*"
			(at 0.02032 2.13233 180)
			(unlocked yes)
			(layer "F.Fab")
			(hide yes)
			(effects
				(font
					(size 0.7874 0.5842)
					(thickness 0.1524)
				)
			)
		)
		(property "Tolerance" "TOL*"
			(at 0.044704 3.05435 180)
			(unlocked yes)
			(layer "Cmts.User")
			(hide yes)
			(effects
				(font
					(size 0.7874 0.5842)
					(thickness 0.1524)
				)
			)
		)
		(property "User Part Number" "PARTNUM*"
			(at 0.02032 4.024884 180)
			(unlocked yes)
			(layer "Cmts.User")
			(hide yes)
			(effects
				(font
					(size 0.7874 0.5842)
					(thickness 0.1524)
				)
			)
		)
		(property "Device Type" "RESISTOR-G155-133R0-01,33OHM,1%"
			(at 0.008382 1.210564 180)
			(unlocked yes)
			(layer "F.Fab")
			(hide yes)
			(effects
				(font
					(size 0.7874 0.5842)
					(thickness 0.1524)
				)
			)
		)
		(duplicate_pad_numbers_are_jumpers no)
		(fp_line
			(start 1.143 0.5588)
			(end 1.143 -0.5588)
			(stroke
				(width 0.1)
				(type default)
			)
			(layer "F.SilkS")
		)
		(fp_line
			(start 1.143 -0.5588)
			(end -1.143 -0.5588)
			(stroke
				(width 0.1)
				(type default)
			)
			(layer "F.SilkS")
		)
		(fp_line
			(start -1.143 0.5588)
			(end 1.143 0.5588)
			(stroke
				(width 0.1)
				(type default)
			)
			(layer "F.SilkS")
		)
		(fp_line
			(start -1.143 -0.5588)
			(end -1.143 0.5588)
			(stroke
				(width 0.1)
				(type default)
			)
			(layer "F.SilkS")
		)
		(fp_rect
			(start -1.143 0.5588)
			(end 1.143 -0.5588)
			(stroke
				(width 0)
				(type default)
			)
			(fill no)
			(layer "F.CrtYd")
		)
		(fp_line
			(start 0.508 0.3048)
			(end 0.508 -0.3048)
			(stroke
				(width 0.1)
				(type default)
			)
			(layer "F.Fab")
		)
		(fp_line
			(start 0.508 -0.3048)
			(end -0.508 -0.3048)
			(stroke
				(width 0.1)
				(type default)
			)
			(layer "F.Fab")
		)
		(fp_line
			(start -0.508 0.3048)
			(end 0.508 0.3048)
			(stroke
				(width 0.1)
				(type default)
			)
			(layer "F.Fab")
		)
		(fp_line
			(start -0.508 -0.3048)
			(end -0.508 0.3048)
			(stroke
				(width 0.1)
				(type default)
			)
			(layer "F.Fab")
		)
		(pad "1" smd rect
			(at -0.5334 0 180)
			(size 0.7112 0.6096)
			(layers "F.Cu" "F.Mask" "F.Paste")
			(net "R_SHT3X_RST_N")
		)
		(pad "2" smd rect
			(at 0.5334 0 180)
			(size 0.7112 0.6096)
			(layers "F.Cu" "F.Mask" "F.Paste")
			(net "FPGA_OUT_SHT3X_RST_N")
		)
		(zone
			(layer "F.Cu")
			(hatch none 0.5)
			(connect_pads
				(clearance 0)
			)
			(min_thickness 0.25)
			(keepout
				(tracks allowed)
				(vias not_allowed)
				(pads allowed)
				(copperpour not_allowed)
				(footprints allowed)
			)
			(placement
				(enabled no)
				(sheetname "")
			)
			(fill
				(thermal_gap 0.5)
				(thermal_bridge_width 0.5)
				(island_removal_mode 0)
			)
			(polygon
				(pts
					(xy 150.457662 -59.4868) (xy 150.305262 -59.4868) (xy 150.305262 -58.8772) (xy 150.457662 -58.8772)
				)
			)
		)
	)
	(footprint ""
		(layer "F.Cu")
		(at 145.8214 -95.4278 180)
		(property "Reference" "R46"
			(at -0.127 -8.92937 0)
			(unlocked yes)
			(layer "F.SilkS")
			(effects
				(font
					(size 0.7874 0.5842)
					(thickness 0.1524)
				)
			)
		)
		(property "Value" "VAL*"
			(at 0.02032 2.13233 180)
			(unlocked yes)
			(layer "F.Fab")
			(hide yes)
			(effects
				(font
					(size 0.7874 0.5842)
					(thickness 0.1524)
				)
			)
		)
		(property "Device Type" "RESISTOR-G155-02672-01,26.7K,1%"
			(at 0.008382 1.210564 180)
			(unlocked yes)
			(layer "F.Fab")
			(hide yes)
			(effects
				(font
					(size 0.7874 0.5842)
					(thickness 0.1524)
				)
			)
		)
		(property "User Part Number" "PARTNUM*"
			(at 0.02032 4.024884 180)
			(unlocked yes)
			(layer "Cmts.User")
			(hide yes)
			(effects
				(font
					(size 0.7874 0.5842)
					(thickness 0.1524)
				)
			)
		)
		(property "Tolerance" "TOL*"
			(at 0.044704 3.05435 180)
			(unlocked yes)
			(layer "Cmts.User")
			(hide yes)
			(effects
				(font
					(size 0.7874 0.5842)
					(thickness 0.1524)
				)
			)
		)
		(duplicate_pad_numbers_are_jumpers no)
		(fp_line
			(start 1.143 0.5588)
			(end 1.143 -0.5588)
			(stroke
				(width 0.1)
				(type default)
			)
			(layer "F.SilkS")
		)
		(fp_line
			(start 1.143 -0.5588)
			(end -1.143 -0.5588)
			(stroke
				(width 0.1)
				(type default)
			)
			(layer "F.SilkS")
		)
		(fp_line
			(start -1.143 0.5588)
			(end 1.143 0.5588)
			(stroke
				(width 0.1)
				(type default)
			)
			(layer "F.SilkS")
		)
		(fp_line
			(start -1.143 -0.5588)
			(end -1.143 0.5588)
			(stroke
				(width 0.1)
				(type default)
			)
			(layer "F.SilkS")
		)
		(fp_rect
			(start 1.143 -0.5588)
			(end -1.143 0.5588)
			(stroke
				(width 0)
				(type default)
			)
			(fill no)
			(layer "F.CrtYd")
		)
		(fp_line
			(start 0.508 0.3048)
			(end 0.508 -0.3048)
			(stroke
				(width 0.1)
				(type default)
			)
			(layer "F.Fab")
		)
		(fp_line
			(start 0.508 -0.3048)
			(end -0.508 -0.3048)
			(stroke
				(width 0.1)
				(type default)
			)
			(layer "F.Fab")
		)
		(fp_line
			(start -0.508 0.3048)
			(end 0.508 0.3048)
			(stroke
				(width 0.1)
				(type default)
			)
			(layer "F.Fab")
		)
		(fp_line
			(start -0.508 -0.3048)
			(end -0.508 0.3048)
			(stroke
				(width 0.1)
				(type default)
			)
			(layer "F.Fab")
		)
		(pad "1" smd rect
			(at -0.5334 0 180)
			(size 0.7112 0.6096)
			(layers "F.Cu" "F.Mask" "F.Paste")
			(net "SG")
		)
		(pad "2" smd rect
			(at 0.5334 0 180)
			(size 0.7112 0.6096)
			(layers "F.Cu" "F.Mask" "F.Paste")
			(net "XP12R0V_A_ISET")
		)
		(zone
			(layer "F.Cu")
			(hatch none 0.5)
			(connect_pads
				(clearance 0)
			)
			(min_thickness 0.25)
			(keepout
				(tracks allowed)
				(vias not_allowed)
				(pads allowed)
				(copperpour not_allowed)
				(footprints allowed)
			)
			(placement
				(enabled no)
				(sheetname "")
			)
			(fill
				(thermal_gap 0.5)
				(thermal_bridge_width 0.5)
				(island_removal_mode 0)
			)
			(polygon
				(pts
					(xy 145.7452 -95.123) (xy 145.8976 -95.123) (xy 145.8976 -95.7326) (xy 145.7452 -95.7326)
				)
			)
		)
	)
	(footprint ""
		(layer "F.Cu")
		(at 96.4438 -72.898 90)
		(property "Reference" "C196"
			(at 19.05 -27.82443 90)
			(unlocked yes)
			(layer "F.SilkS")
			(effects
				(font
					(size 0.7874 0.5842)
					(thickness 0.1524)
				)
			)
		)
		(property "Value" "VAL*"
			(at 0.0762 2.067306 90)
			(unlocked yes)
			(layer "F.Fab")
			(hide yes)
			(effects
				(font
					(size 0.7874 0.5842)
					(thickness 0.1524)
				)
			)
		)
		(property "Tolerance" "TOL*"
			(at 0.0762 3.032506 90)
			(unlocked yes)
			(layer "Cmts.User")
			(hide yes)
			(effects
				(font
					(size 0.7874 0.5842)
					(thickness 0.1524)
				)
			)
		)
		(property "User Part Number" "PARTNUM*"
			(at 0.1016 4.023106 90)
			(unlocked yes)
			(layer "Cmts.User")
			(hide yes)
			(effects
				(font
					(size 0.7874 0.5842)
					(thickness 0.1524)
				)
			)
		)
		(property "Device Type" "CAPACITOR-G105-0B104-EK,0.1UF,A"
			(at 0.0508 1.127506 90)
			(unlocked yes)
			(layer "F.Fab")
			(hide yes)
			(effects
				(font
					(size 0.7874 0.5842)
					(thickness 0.1524)
				)
			)
		)
		(duplicate_pad_numbers_are_jumpers no)
		(fp_line
			(start 1.143 -0.5588)
			(end -1.143 -0.5588)
			(stroke
				(width 0.1)
				(type default)
			)
			(layer "F.SilkS")
		)
		(fp_line
			(start -1.143 -0.5588)
			(end -1.143 0.5588)
			(stroke
				(width 0.1)
				(type default)
			)
			(layer "F.SilkS")
		)
		(fp_line
			(start 1.143 0.5588)
			(end 1.143 -0.5588)
			(stroke
				(width 0.1)
				(type default)
			)
			(layer "F.SilkS")
		)
		(fp_line
			(start -1.143 0.5588)
			(end 1.143 0.5588)
			(stroke
				(width 0.1)
				(type default)
			)
			(layer "F.SilkS")
		)
		(fp_rect
			(start 1.143 -0.5588)
			(end -1.143 0.5588)
			(stroke
				(width 0)
				(type default)
			)
			(fill no)
			(layer "F.CrtYd")
		)
		(fp_line
			(start 0.508 -0.3048)
			(end -0.508 -0.3048)
			(stroke
				(width 0.1)
				(type default)
			)
			(layer "F.Fab")
		)
		(fp_line
			(start -0.508 -0.3048)
			(end -0.508 0.3048)
			(stroke
				(width 0.1)
				(type default)
			)
			(layer "F.Fab")
		)
		(fp_line
			(start 0.508 0.3048)
			(end 0.508 -0.3048)
			(stroke
				(width 0.1)
				(type default)
			)
			(layer "F.Fab")
		)
		(fp_line
			(start -0.508 0.3048)
			(end 0.508 0.3048)
			(stroke
				(width 0.1)
				(type default)
			)
			(layer "F.Fab")
		)
		(pad "1" smd rect
			(at -0.5334 0 90)
			(size 0.7112 0.6096)
			(layers "F.Cu" "F.Mask" "F.Paste")
			(net "XP1R2V_FPGA")
		)
		(pad "2" smd rect
			(at 0.5334 0 90)
			(size 0.7112 0.6096)
			(layers "F.Cu" "F.Mask" "F.Paste")
			(net "SG")
		)
		(zone
			(layer "F.Cu")
			(hatch none 0.5)
			(connect_pads
				(clearance 0)
			)
			(min_thickness 0.25)
			(keepout
				(tracks allowed)
				(vias not_allowed)
				(pads allowed)
				(copperpour not_allowed)
				(footprints allowed)
			)
			(placement
				(enabled no)
				(sheetname "")
			)
			(fill
				(thermal_gap 0.5)
				(thermal_bridge_width 0.5)
				(island_removal_mode 0)
			)
			(polygon
				(pts
					(xy 96.139 -72.9742) (xy 96.139 -72.8218) (xy 96.7486 -72.8218) (xy 96.7486 -72.9742)
				)
			)
		)
	)
)
